# T6G (Grand Teton) — schematic netlist excerpt (pin names and nets, part order shuffled) for the footprints in the layout excerpt that follows; sources: Cadence DE-HDL packaged netlist, KiCad conversion of 04192023_DAF0TMB3IC0_F0TG_MB_C_brd_V02_OCP.brd

C798  Q_CAP  100UF 4V 20% X6S  pkg C0805  page 301 : A = P0V9_CPU0_RT2_2A ; B = GND
R3266  Q_RES  4.7K 1% CHIP  pkg 0402LF  page 111 : A = P3V3_AUX ; B = FM_P2E_MODE
PC569  Q_CAP  10PF 50V 1% NPO  pkg 0402  page 190 : A = P3V3_AUX_FB ; B = P3V3_AUX

(kicad_pcb
	(version 20260206)
	(generator "pcbnew")
	(generator_version "10.0")
	(general
		(thickness 1.6)
		(legacy_teardrops no)
	)
	(paper "A4")
	(title_block
		(title "04192023_DAF0TMB3IC0_F0TG_MB_C_brd_V02_OCP.brd")
		(comment 1 "Grand Teton / footprints 2763-2765 of 8354")
	)
	(layers
		(0 "F.Cu" signal "TOP")
		(4 "In1.Cu" signal "GND")
		(6 "In2.Cu" signal "IN1")
		(8 "In3.Cu" signal "GND1")
		(10 "In4.Cu" signal "IN2")
		(12 "In5.Cu" signal "GND2")
		(14 "In6.Cu" signal "IN3")
		(16 "In7.Cu" signal "GND3")
		(18 "In8.Cu" signal "VCC")
		(20 "In9.Cu" signal "VCC1")
		(22 "In10.Cu" signal "GND4")
		(24 "In11.Cu" signal "IN4")
		(26 "In12.Cu" signal "GND5")
		(28 "In13.Cu" signal "IN5")
		(30 "In14.Cu" signal "GND6")
		(32 "In15.Cu" signal "IN6")
		(34 "In16.Cu" signal "GND7")
		(2 "B.Cu" signal "BOTTOM")
		(9 "F.Adhes" user "F.Adhesive")
		(11 "B.Adhes" user "B.Adhesive")
		(13 "F.Paste" user "Package Geometry/Pastemask Top")
		(15 "B.Paste" user "Package Geometry/Pastemask Bottom")
		(5 "F.SilkS" user "Ref Des/Silkscreen Top")
		(7 "B.SilkS" user "Ref Des/Silkscreen Bottom")
		(1 "F.Mask" user "Board Geometry/Soldermask Top")
		(3 "B.Mask" user "Board Geometry/Soldermask Bottom")
		(17 "Dwgs.User" user "User.Drawings")
		(19 "Cmts.User" user "User.Comments")
		(21 "Eco1.User" user "User.Eco1")
		(23 "Eco2.User" user "User.Eco2")
		(25 "Edge.Cuts" user "Board Geometry/Outline")
		(27 "Margin" user)
		(31 "F.CrtYd" user "Package Geometry/Place Bound Top")
		(29 "B.CrtYd" user "Package Geometry/Place Bound Bottom")
		(35 "F.Fab" user "Ref Des/Assembly Top")
		(33 "B.Fab" user "Ref Des/Assembly Bottom")
	)
	(footprint ""
		(layer "F.Cu")
		(at 455.534776 -46.264576 -90)
		(property "Reference" "PC569"
			(at 0 0 270)
			(layer "F.SilkS")
			(hide yes)
			(effects
				(font
					(size 1.27 1.27)
				)
			)
		)
		(property "Value" ""
			(at 0 0 270)
			(layer "F.Fab")
			(effects
				(font
					(size 1.27 1.27)
				)
			)
		)
		(duplicate_pad_numbers_are_jumpers no)
		(fp_line
			(start -0.7874 0.4064)
			(end -0.7874 -0.4064)
			(stroke
				(width 0.1524)
				(type default)
			)
			(layer "F.SilkS")
		)
		(fp_line
			(start 0.7874 0.4064)
			(end -0.7874 0.4064)
			(stroke
				(width 0.1524)
				(type default)
			)
			(layer "F.SilkS")
		)
		(fp_line
			(start -0.7874 -0.4064)
			(end 0.7874 -0.4064)
			(stroke
				(width 0.1524)
				(type default)
			)
			(layer "F.SilkS")
		)
		(fp_line
			(start 0.7874 -0.4064)
			(end 0.7874 0.4064)
			(stroke
				(width 0.1524)
				(type default)
			)
			(layer "F.SilkS")
		)
		(fp_line
			(start -0.67945 0.3048)
			(end -0.67945 -0.305054)
			(stroke
				(width 0.1)
				(type default)
			)
			(layer "F.Fab")
		)
		(fp_line
			(start -0.12065 0.3048)
			(end -0.67945 0.3048)
			(stroke
				(width 0.1)
				(type default)
			)
			(layer "F.Fab")
		)
		(fp_line
			(start 0.120396 0.3048)
			(end 0.120396 0.2794)
			(stroke
				(width 0.1)
				(type default)
			)
			(layer "F.Fab")
		)
		(fp_line
			(start 0.67945 0.3048)
			(end 0.120396 0.3048)
			(stroke
				(width 0.1)
				(type default)
			)
			(layer "F.Fab")
		)
		(fp_line
			(start -0.12065 0.2794)
			(end -0.12065 0.3048)
			(stroke
				(width 0.1)
				(type default)
			)
			(layer "F.Fab")
		)
		(fp_line
			(start 0.120396 0.2794)
			(end -0.12065 0.2794)
			(stroke
				(width 0.1)
				(type default)
			)
			(layer "F.Fab")
		)
		(fp_line
			(start -0.12065 -0.2794)
			(end 0.12065 -0.2794)
			(stroke
				(width 0.1)
				(type default)
			)
			(layer "F.Fab")
		)
		(fp_line
			(start 0.12065 -0.2794)
			(end 0.12065 -0.3048)
			(stroke
				(width 0.1)
				(type default)
			)
			(layer "F.Fab")
		)
		(fp_line
			(start 0.12065 -0.3048)
			(end 0.67945 -0.3048)
			(stroke
				(width 0.1)
				(type default)
			)
			(layer "F.Fab")
		)
		(fp_line
			(start 0.67945 -0.3048)
			(end 0.67945 0.3048)
			(stroke
				(width 0.1)
				(type default)
			)
			(layer "F.Fab")
		)
		(fp_line
			(start -0.67945 -0.305054)
			(end -0.12065 -0.305054)
			(stroke
				(width 0.1)
				(type default)
			)
			(layer "F.Fab")
		)
		(fp_line
			(start -0.12065 -0.305054)
			(end -0.12065 -0.2794)
			(stroke
				(width 0.1)
				(type default)
			)
			(layer "F.Fab")
		)
		(pad "1" smd circle
			(at -0.40005 0 270)
			(size 0 0)
			(layers "F.Cu" "F.Mask" "F.Paste")
			(net "P3V3_AUX_FB")
		)
		(pad "2" smd circle
			(at 0.40005 0 270)
			(size 0 0)
			(layers "F.Cu" "F.Mask" "F.Paste")
			(net "P3V3_AUX")
		)
	)
	(footprint ""
		(layer "F.Cu")
		(at 38.697662 -419.249098 90)
		(property "Reference" "R3266"
			(at 0 0 90)
			(layer "F.SilkS")
			(hide yes)
			(effects
				(font
					(size 1.27 1.27)
				)
			)
		)
		(property "Value" ""
			(at 0 0 90)
			(layer "F.Fab")
			(effects
				(font
					(size 1.27 1.27)
				)
			)
		)
		(duplicate_pad_numbers_are_jumpers no)
		(fp_line
			(start 0.7874 -0.4064)
			(end 0.7874 0.4064)
			(stroke
				(width 0.1524)
				(type default)
			)
			(layer "F.SilkS")
		)
		(fp_line
			(start -0.7874 -0.4064)
			(end 0.7874 -0.4064)
			(stroke
				(width 0.1524)
				(type default)
			)
			(layer "F.SilkS")
		)
		(fp_line
			(start 0.7874 0.4064)
			(end -0.7874 0.4064)
			(stroke
				(width 0.1524)
				(type default)
			)
			(layer "F.SilkS")
		)
		(fp_line
			(start -0.7874 0.4064)
			(end -0.7874 -0.4064)
			(stroke
				(width 0.1524)
				(type default)
			)
			(layer "F.SilkS")
		)
		(fp_line
			(start -0.12065 -0.305054)
			(end -0.12065 -0.2794)
			(stroke
				(width 0.1)
				(type default)
			)
			(layer "F.Fab")
		)
		(fp_line
			(start -0.67945 -0.305054)
			(end -0.12065 -0.305054)
			(stroke
				(width 0.1)
				(type default)
			)
			(layer "F.Fab")
		)
		(fp_line
			(start 0.67945 -0.3048)
			(end 0.67945 0.3048)
			(stroke
				(width 0.1)
				(type default)
			)
			(layer "F.Fab")
		)
		(fp_line
			(start 0.12065 -0.3048)
			(end 0.67945 -0.3048)
			(stroke
				(width 0.1)
				(type default)
			)
			(layer "F.Fab")
		)
		(fp_line
			(start 0.12065 -0.2794)
			(end 0.12065 -0.3048)
			(stroke
				(width 0.1)
				(type default)
			)
			(layer "F.Fab")
		)
		(fp_line
			(start -0.12065 -0.2794)
			(end 0.12065 -0.2794)
			(stroke
				(width 0.1)
				(type default)
			)
			(layer "F.Fab")
		)
		(fp_line
			(start 0.120396 0.2794)
			(end -0.12065 0.2794)
			(stroke
				(width 0.1)
				(type default)
			)
			(layer "F.Fab")
		)
		(fp_line
			(start -0.12065 0.2794)
			(end -0.12065 0.3048)
			(stroke
				(width 0.1)
				(type default)
			)
			(layer "F.Fab")
		)
		(fp_line
			(start 0.67945 0.3048)
			(end 0.120396 0.3048)
			(stroke
				(width 0.1)
				(type default)
			)
			(layer "F.Fab")
		)
		(fp_line
			(start 0.120396 0.3048)
			(end 0.120396 0.2794)
			(stroke
				(width 0.1)
				(type default)
			)
			(layer "F.Fab")
		)
		(fp_line
			(start -0.12065 0.3048)
			(end -0.67945 0.3048)
			(stroke
				(width 0.1)
				(type default)
			)
			(layer "F.Fab")
		)
		(fp_line
			(start -0.67945 0.3048)
			(end -0.67945 -0.305054)
			(stroke
				(width 0.1)
				(type default)
			)
			(layer "F.Fab")
		)
		(pad "1" smd circle
			(at -0.40005 0 90)
			(size 0 0)
			(layers "F.Cu" "F.Mask" "F.Paste")
			(net "P3V3_AUX")
		)
		(pad "2" smd circle
			(at 0.40005 0 90)
			(size 0 0)
			(layers "F.Cu" "F.Mask" "F.Paste")
			(net "FM_P2E_MODE")
		)
	)
	(footprint ""
		(layer "F.Cu")
		(at 426.213778 -398.71523)
		(property "Reference" "C798"
			(at 0 0 0)
			(layer "F.SilkS")
			(hide yes)
			(effects
				(font
					(size 1.27 1.27)
				)
			)
		)
		(property "Value" ""
			(at 0 0 0)
			(layer "F.Fab")
			(effects
				(font
					(size 1.27 1.27)
				)
			)
		)
		(duplicate_pad_numbers_are_jumpers no)
		(fp_line
			(start -1.524 -0.762)
			(end 1.524 -0.762)
			(stroke
				(width 0.1524)
				(type default)
			)
			(layer "F.SilkS")
		)
		(fp_line
			(start -1.524 0.762)
			(end -1.524 -0.762)
			(stroke
				(width 0.1524)
				(type default)
			)
			(layer "F.SilkS")
		)
		(fp_line
			(start 1.524 -0.762)
			(end 1.524 0.762)
			(stroke
				(width 0.1524)
				(type default)
			)
			(layer "F.SilkS")
		)
		(fp_line
			(start 1.524 0.762)
			(end -1.524 0.762)
			(stroke
				(width 0.1524)
				(type default)
			)
			(layer "F.SilkS")
		)
		(fp_line
			(start -1.1049 -0.724916)
			(end -1.1049 0.724916)
			(stroke
				(width 0.1)
				(type default)
			)
			(layer "F.Fab")
		)
		(fp_line
			(start -1.1049 0.724916)
			(end 1.1049 0.724916)
			(stroke
				(width 0.1)
				(type default)
			)
			(layer "F.Fab")
		)
		(fp_line
			(start 1.1049 -0.724916)
			(end -1.1049 -0.724916)
			(stroke
				(width 0.1)
				(type default)
			)
			(layer "F.Fab")
		)
		(fp_line
			(start 1.1049 0.724916)
			(end 1.1049 -0.724916)
			(stroke
				(width 0.1)
				(type default)
			)
			(layer "F.Fab")
		)
		(pad "1" smd rect
			(at -0.889 0 180)
			(size 1.016 1.27)
			(layers "F.Cu" "F.Mask" "F.Paste")
			(net "P0V9_CPU0_RT2_2A")
		)
		(pad "2" smd rect
			(at 0.889 0 180)
			(size 1.016 1.27)
			(layers "F.Cu" "F.Mask" "F.Paste")
			(net "GND")
		)
	)
)
